# Stackup_F0T_PDB_Converter_10L_2p36mm_IT-170GT_RTF_Rev0p2_20211201.xls — Special processing (pcb-stackup)
| Special processing : |  |
| Golden Finger(金手指) | No |
| VIPPO(Via in Pad樹脂填孔) | No |
| Back Drill(背鑽) with epoxy plug/fill | No |
| Back Drill(背鑽) without epoxy plug/fill | No |
| Laser Drill(HDI雷射鑽孔) | No |
| Low profile oxide(低棕化) | No |
